FILE_TYPE = CONNECTIVITY;
{Allegro Design Entry HDL 17.2-2016 S081 (4005846) 1/11/2022}
"PAGE_NUMBER" = 3;
0"NC";
END.
